(kicad_pcb
	(version 20221018)
	(generator pcbnew)
	(general
    (thickness 1.62)
  )
	(paper "A4")
	(title_block
    (title "ECP5 - Datacenter Secure Control Module (DC-SCM)")
    (date "2024-07-01")
    (rev "1.2.1")
		(comment 9 "footprints 392-400 of 506")
	)
	(layers
    (0 "F.Cu" signal)
    (1 "In1.Cu" power)
    (2 "In2.Cu" signal)
    (3 "In3.Cu" power)
    (4 "In4.Cu" power)
    (5 "In5.Cu" signal)
    (6 "In6.Cu" power)
    (31 "B.Cu" signal)
    (32 "B.Adhes" user "B.Adhesive")
    (33 "F.Adhes" user "F.Adhesive")
    (34 "B.Paste" user)
    (35 "F.Paste" user)
    (36 "B.SilkS" user "B.Silkscreen")
    (37 "F.SilkS" user "F.Silkscreen")
    (38 "B.Mask" user)
    (39 "F.Mask" user)
    (40 "Dwgs.User" user "User.Drawings")
    (41 "Cmts.User" user "User.Comments")
    (42 "Eco1.User" user "User.Eco1")
    (43 "Eco2.User" user "User.Eco2")
    (44 "Edge.Cuts" user)
    (45 "Margin" user)
    (46 "B.CrtYd" user "B.Courtyard")
    (47 "F.CrtYd" user "F.Courtyard")
    (48 "B.Fab" user)
    (49 "F.Fab" user)
  )
	(footprint "antmicro-footprints:C_0402_1005Metric" (layer "B.Cu")
    (at 95 83.5)
    (descr "Capacitor SMD 0402")
    (tags "capacitor SMD 0402")
    (property "Author" "Antmicro")
    (property "Dielectric" "X5R")
    (property "License" "Apache-2.0")
    (property "MPN" "GRM155R61H104KE14D")
    (property "Manufacturer" "Murata")
    (property "Public" "False")
    (property "Sheetfile" "ethernet.kicad_sch")
    (property "Sheetname" "Ethernet")
    (property "Val" "100n")
    (property "Voltage" "50V")
    (property "ki_description" "SMD Multilayer Ceramic Capacitor, 0.1 µF, 50 V, 0402 [1005 Metric], ± 10%, X5R, GRM Series")
    (property "ki_keywords" "0402, SMT, CAPACITOR, PASSIVE, CERAMIC, MLCC")
    (attr smd)
    (fp_text reference "C30" (at -0.1 -2.03) (layer "B.SilkS")
        (effects (font (size 0.7 0.7) (thickness 0.127)) (justify mirror))
    )
    (fp_text value "C_100n_0402" (at 0 -1.17) (layer "B.Fab")
        (effects (font (size 1 1) (thickness 0.15)) (justify mirror))
    )
    (fp_text user "${REFERENCE}" (at 0 0) (layer "B.Fab")
        (effects (font (size 0.25 0.25) (thickness 0.04)) (justify mirror))
    )
    (fp_text user "Author: Antmicro" (at -0.939 -3.399 180) (layer "B.Fab") hide
        (effects (font (size 0.7 0.7) (thickness 0.15)) (justify left bottom mirror))
    )
    (fp_text user "License: Apache-2.0" (at -0.939 -5.799 180) (layer "B.Fab") hide
        (effects (font (size 0.7 0.7) (thickness 0.15)) (justify left bottom mirror))
    )
    (fp_rect (start -0.925 0.47) (end 0.925 -0.47)
      (stroke (width 0.05) (type default)) (fill none) (layer "B.CrtYd"))
    (fp_line (start -0.494 -0.248) (end -0.494 0.25)
      (stroke (width 0.15) (type solid)) (layer "B.Fab"))
    (fp_line (start -0.494 0.25) (end 0.504 0.25)
      (stroke (width 0.15) (type solid)) (layer "B.Fab"))
    (fp_line (start 0.504 -0.248) (end -0.494 -0.248)
      (stroke (width 0.15) (type solid)) (layer "B.Fab"))
    (fp_line (start 0.504 0.25) (end 0.504 -0.248)
      (stroke (width 0.15) (type solid)) (layer "B.Fab"))
    (pad "1" smd roundrect (at -0.48 0) (size 0.59 0.64) (layers "B.Cu" "B.Paste" "B.Mask") (roundrect_rratio 0.25)
      (net 1 "GND") (pintype "passive"))
    (pad "2" smd roundrect (at 0.48 0) (size 0.59 0.64) (layers "B.Cu" "B.Paste" "B.Mask") (roundrect_rratio 0.25)
      (net 14 "Net-(J1-TRCT4)") (pintype "passive"))
  )
	(footprint "antmicro-footprints:R_0402_1005Metric" (layer "B.Cu")
    (at 81.09 122.595)
    (descr "Resistor SMD 0402")
    (tags "resistor SMD 0402")
    (property "Author" "Antmicro")
    (property "License" "Apache-2.0")
    (property "MPN" "CR0402-FX-51R0GLF")
    (property "Manufacturer" "Bourns")
    (property "Public" "False")
    (property "Sheetfile" "ddr3.kicad_sch")
    (property "Sheetname" "DDR3")
    (property "Tolerance" "1%")
    (property "Val" "51R")
    (property "ki_description" "SMD Chip Resistor, 51 ohm, ± 1%, 63 mW, 0402 [1005 Metric], Thick Film, General Purpose")
    (property "ki_keywords" "0402, SMT, RESISTOR, PASSIVE")
    (attr smd)
    (fp_text reference "R83" (at 0.23 -0.86 180) (layer "B.SilkS")
        (effects (font (size 0.7 0.7) (thickness 0.127)) (justify mirror))
    )
    (fp_text value "R_51R_0402" (at 0 -1.17) (layer "B.Fab")
        (effects (font (size 1 1) (thickness 0.15)) (justify mirror))
    )
    (fp_text user "Author: Antmicro" (at -0.95 -4.169 180) (layer "B.Fab") hide
        (effects (font (size 0.7 0.7) (thickness 0.15)) (justify left bottom mirror))
    )
    (fp_text user "${REFERENCE}" (at 0 0) (layer "B.Fab")
        (effects (font (size 0.25 0.25) (thickness 0.04)) (justify mirror))
    )
    (fp_text user "License: Apache-2.0" (at -0.95 -5.169 180) (layer "B.Fab") hide
        (effects (font (size 0.7 0.7) (thickness 0.15)) (justify left bottom mirror))
    )
    (fp_rect (start -0.925 0.47) (end 0.925 -0.47)
      (stroke (width 0.05) (type default)) (fill none) (layer "B.CrtYd"))
    (fp_rect (start -0.5 0.25) (end 0.5 -0.25)
      (stroke (width 0.15) (type solid)) (fill none) (layer "B.Fab"))
    (pad "1" smd roundrect (at -0.48 0) (size 0.59 0.64) (layers "B.Cu" "B.Paste" "B.Mask") (roundrect_rratio 0.25)
      (net 228 "Net-(C94-Pad1)") (pintype "passive"))
    (pad "2" smd roundrect (at 0.48 0) (size 0.59 0.64) (layers "B.Cu" "B.Paste" "B.Mask") (roundrect_rratio 0.25)
      (net 262 "DDR3_CLK-") (pintype "passive"))
  )
	(footprint "antmicro-footprints:C_0402_1005Metric" (layer "B.Cu")
    (at 83.15 138.765 -90)
    (descr "Capacitor SMD 0402")
    (tags "capacitor SMD 0402")
    (property "Author" "Antmicro")
    (property "Dielectric" "")
    (property "License" "Apache-2.0")
    (property "MPN" "C1005X5R1E474M050BB")
    (property "Manufacturer" "TDK")
    (property "Public" "False")
    (property "Sheetfile" "rot.kicad_sch")
    (property "Sheetname" "RoT")
    (property "Val" "470n")
    (property "Voltage" "")
    (property "ki_description" "SMD Multilayer Ceramic Capacitor, 0.47 µF, 25 V, 0402 [1005 Metric], ± 20%, X5R, C")
    (property "ki_keywords" "0402, SMT, CAPACITOR, PASSIVE, CERAMIC, MLCC")
    (attr smd)
    (fp_text reference "C43" (at -3.085 0.199996 90) (layer "B.SilkS")
        (effects (font (size 0.7 0.7) (thickness 0.127)) (justify mirror))
    )
    (fp_text value "C_470n_0402" (at 0 -1.17 90) (layer "B.Fab")
        (effects (font (size 1 1) (thickness 0.15)) (justify mirror))
    )
    (fp_text user "${REFERENCE}" (at 0 0 90) (layer "B.Fab")
        (effects (font (size 0.25 0.25) (thickness 0.04)) (justify mirror))
    )
    (fp_text user "Author: Antmicro" (at -0.939 -3.399 90) (layer "B.Fab") hide
        (effects (font (size 0.7 0.7) (thickness 0.15)) (justify left bottom mirror))
    )
    (fp_text user "License: Apache-2.0" (at -0.939 -5.799 90) (layer "B.Fab") hide
        (effects (font (size 0.7 0.7) (thickness 0.15)) (justify left bottom mirror))
    )
    (fp_rect (start -0.925 0.47) (end 0.925 -0.47)
      (stroke (width 0.05) (type default)) (fill none) (layer "B.CrtYd"))
    (fp_line (start -0.494 -0.248) (end -0.494 0.25)
      (stroke (width 0.15) (type solid)) (layer "B.Fab"))
    (fp_line (start -0.494 0.25) (end 0.504 0.25)
      (stroke (width 0.15) (type solid)) (layer "B.Fab"))
    (fp_line (start 0.504 -0.248) (end -0.494 -0.248)
      (stroke (width 0.15) (type solid)) (layer "B.Fab"))
    (fp_line (start 0.504 0.25) (end 0.504 -0.248)
      (stroke (width 0.15) (type solid)) (layer "B.Fab"))
    (pad "1" smd roundrect (at -0.48 0 270) (size 0.59 0.64) (layers "B.Cu" "B.Paste" "B.Mask") (roundrect_rratio 0.25)
      (net 1 "GND") (pintype "passive"))
    (pad "2" smd roundrect (at 0.48 0 270) (size 0.59 0.64) (layers "B.Cu" "B.Paste" "B.Mask") (roundrect_rratio 0.25)
      (net 2 "VCC3V3") (pintype "passive"))
  )
	(footprint "antmicro-footprints:C_0402_1005Metric" (layer "B.Cu")
    (at 82.6 130.55)
    (descr "Capacitor SMD 0402")
    (tags "capacitor SMD 0402")
    (property "Author" "Antmicro")
    (property "Dielectric" "")
    (property "License" "Apache-2.0")
    (property "MPN" "C1005X5R1E474M050BB")
    (property "Manufacturer" "TDK")
    (property "Public" "False")
    (property "Sheetfile" "rot.kicad_sch")
    (property "Sheetname" "RoT")
    (property "Val" "470n")
    (property "Voltage" "")
    (property "ki_description" "SMD Multilayer Ceramic Capacitor, 0.47 µF, 25 V, 0402 [1005 Metric], ± 20%, X5R, C")
    (property "ki_keywords" "0402, SMT, CAPACITOR, PASSIVE, CERAMIC, MLCC")
    (attr smd)
    (fp_text reference "C44" (at 0.02 -1.035) (layer "B.SilkS")
        (effects (font (size 0.7 0.7) (thickness 0.127)) (justify mirror))
    )
    (fp_text value "C_470n_0402" (at 0 -1.17) (layer "B.Fab")
        (effects (font (size 1 1) (thickness 0.15)) (justify mirror))
    )
    (fp_text user "${REFERENCE}" (at 0 0) (layer "B.Fab")
        (effects (font (size 0.25 0.25) (thickness 0.04)) (justify mirror))
    )
    (fp_text user "License: Apache-2.0" (at -0.939 -5.799 180) (layer "B.Fab") hide
        (effects (font (size 0.7 0.7) (thickness 0.15)) (justify left bottom mirror))
    )
    (fp_text user "Author: Antmicro" (at -0.939 -3.399 180) (layer "B.Fab") hide
        (effects (font (size 0.7 0.7) (thickness 0.15)) (justify left bottom mirror))
    )
    (fp_rect (start -0.925 0.47) (end 0.925 -0.47)
      (stroke (width 0.05) (type default)) (fill none) (layer "B.CrtYd"))
    (fp_line (start -0.494 -0.248) (end -0.494 0.25)
      (stroke (width 0.15) (type solid)) (layer "B.Fab"))
    (fp_line (start -0.494 0.25) (end 0.504 0.25)
      (stroke (width 0.15) (type solid)) (layer "B.Fab"))
    (fp_line (start 0.504 -0.248) (end -0.494 -0.248)
      (stroke (width 0.15) (type solid)) (layer "B.Fab"))
    (fp_line (start 0.504 0.25) (end 0.504 -0.248)
      (stroke (width 0.15) (type solid)) (layer "B.Fab"))
    (pad "1" smd roundrect (at -0.48 0) (size 0.59 0.64) (layers "B.Cu" "B.Paste" "B.Mask") (roundrect_rratio 0.25)
      (net 1 "GND") (pintype "passive"))
    (pad "2" smd roundrect (at 0.48 0) (size 0.59 0.64) (layers "B.Cu" "B.Paste" "B.Mask") (roundrect_rratio 0.25)
      (net 2 "VCC3V3") (pintype "passive"))
  )
	(footprint "antmicro-footprints:C_0402_1005Metric" (layer "B.Cu")
    (at 71.4 130.65)
    (descr "Capacitor SMD 0402")
    (tags "capacitor SMD 0402")
    (property "Author" "Antmicro")
    (property "Dielectric" "")
    (property "License" "Apache-2.0")
    (property "MPN" "C1005X5R1E474M050BB")
    (property "Manufacturer" "TDK")
    (property "Public" "False")
    (property "Sheetfile" "rot.kicad_sch")
    (property "Sheetname" "RoT")
    (property "Val" "470n")
    (property "Voltage" "")
    (property "ki_description" "SMD Multilayer Ceramic Capacitor, 0.47 µF, 25 V, 0402 [1005 Metric], ± 20%, X5R, C")
    (property "ki_keywords" "0402, SMT, CAPACITOR, PASSIVE, CERAMIC, MLCC")
    (attr smd)
    (fp_text reference "C45" (at 0 1.17) (layer "B.SilkS")
        (effects (font (size 0.7 0.7) (thickness 0.127)) (justify mirror))
    )
    (fp_text value "C_470n_0402" (at 0 -1.17) (layer "B.Fab")
        (effects (font (size 1 1) (thickness 0.15)) (justify mirror))
    )
    (fp_text user "License: Apache-2.0" (at -0.939 -5.799 180) (layer "B.Fab") hide
        (effects (font (size 0.7 0.7) (thickness 0.15)) (justify left bottom mirror))
    )
    (fp_text user "${REFERENCE}" (at 0 0) (layer "B.Fab")
        (effects (font (size 0.25 0.25) (thickness 0.04)) (justify mirror))
    )
    (fp_text user "Author: Antmicro" (at -0.939 -3.399 180) (layer "B.Fab") hide
        (effects (font (size 0.7 0.7) (thickness 0.15)) (justify left bottom mirror))
    )
    (fp_rect (start -0.925 0.47) (end 0.925 -0.47)
      (stroke (width 0.05) (type default)) (fill none) (layer "B.CrtYd"))
    (fp_line (start -0.494 -0.248) (end -0.494 0.25)
      (stroke (width 0.15) (type solid)) (layer "B.Fab"))
    (fp_line (start -0.494 0.25) (end 0.504 0.25)
      (stroke (width 0.15) (type solid)) (layer "B.Fab"))
    (fp_line (start 0.504 -0.248) (end -0.494 -0.248)
      (stroke (width 0.15) (type solid)) (layer "B.Fab"))
    (fp_line (start 0.504 0.25) (end 0.504 -0.248)
      (stroke (width 0.15) (type solid)) (layer "B.Fab"))
    (pad "1" smd roundrect (at -0.48 0) (size 0.59 0.64) (layers "B.Cu" "B.Paste" "B.Mask") (roundrect_rratio 0.25)
      (net 1 "GND") (pintype "passive"))
    (pad "2" smd roundrect (at 0.48 0) (size 0.59 0.64) (layers "B.Cu" "B.Paste" "B.Mask") (roundrect_rratio 0.25)
      (net 2 "VCC3V3") (pintype "passive"))
  )
	(footprint "antmicro-footprints:R_0402_1005Metric" (layer "B.Cu")
    (at 78.975 147.8 90)
    (descr "Resistor SMD 0402")
    (tags "resistor SMD 0402")
    (property "Author" "Antmicro")
    (property "License" "Apache-2.0")
    (property "MPN" "CR0402-FX-4701GLF")
    (property "Manufacturer" "Bourns")
    (property "Public" "False")
    (property "Sheetfile" "rot.kicad_sch")
    (property "Sheetname" "RoT")
    (property "Tolerance" "1%")
    (property "Val" "4k7")
    (property "ki_description" "SMD Chip Resistor, 4.7 kohm, ± 1%, 62.5 mW, 0402 [1005 Metric], Thick Film, General Purpose")
    (property "ki_keywords" "0402, SMT, RESISTOR, PASSIVE")
    (attr smd)
    (fp_text reference "R21" (at -2.75 1.125 270) (layer "B.SilkS")
        (effects (font (size 0.7 0.7) (thickness 0.127)) (justify mirror))
    )
    (fp_text value "R_4k7_0402" (at 0 -1.17 270) (layer "B.Fab")
        (effects (font (size 1 1) (thickness 0.15)) (justify mirror))
    )
    (fp_text user "License: Apache-2.0" (at -0.95 -5.169 270) (layer "B.Fab") hide
        (effects (font (size 0.7 0.7) (thickness 0.15)) (justify left bottom mirror))
    )
    (fp_text user "${REFERENCE}" (at 0 0 270) (layer "B.Fab")
        (effects (font (size 0.25 0.25) (thickness 0.04)) (justify mirror))
    )
    (fp_text user "Author: Antmicro" (at -0.95 -4.169 270) (layer "B.Fab") hide
        (effects (font (size 0.7 0.7) (thickness 0.15)) (justify left bottom mirror))
    )
    (fp_rect (start -0.925 0.47) (end 0.925 -0.47)
      (stroke (width 0.05) (type default)) (fill none) (layer "B.CrtYd"))
    (fp_rect (start -0.5 0.25) (end 0.5 -0.25)
      (stroke (width 0.15) (type solid)) (fill none) (layer "B.Fab"))
    (pad "1" smd roundrect (at -0.48 0 90) (size 0.59 0.64) (layers "B.Cu" "B.Paste" "B.Mask") (roundrect_rratio 0.25)
      (net 2 "VCC3V3") (pintype "passive"))
    (pad "2" smd roundrect (at 0.48 0 90) (size 0.59 0.64) (layers "B.Cu" "B.Paste" "B.Mask") (roundrect_rratio 0.25)
      (net 134 "QSPIB2_CS_N") (pintype "passive"))
  )
	(footprint "antmicro-footprints:R_0402_1005Metric" (layer "B.Cu")
    (at 67.725 138.85 90)
    (descr "Resistor SMD 0402")
    (tags "resistor SMD 0402")
    (property "Author" "Antmicro")
    (property "License" "Apache-2.0")
    (property "MPN" "CR0402-FX-4701GLF")
    (property "Manufacturer" "Bourns")
    (property "Public" "False")
    (property "Sheetfile" "rot.kicad_sch")
    (property "Sheetname" "RoT")
    (property "Tolerance" "1%")
    (property "Val" "4k7")
    (property "ki_description" "SMD Chip Resistor, 4.7 kohm, ± 1%, 62.5 mW, 0402 [1005 Metric], Thick Film, General Purpose")
    (property "ki_keywords" "0402, SMT, RESISTOR, PASSIVE")
    (attr smd)
    (fp_text reference "R23" (at -2.95 0.061666 90) (layer "B.SilkS")
        (effects (font (size 0.7 0.7) (thickness 0.127)) (justify mirror))
    )
    (fp_text value "R_4k7_0402" (at 0 -1.17 90) (layer "B.Fab")
        (effects (font (size 1 1) (thickness 0.15)) (justify mirror))
    )
    (fp_text user "${REFERENCE}" (at 0 0 90) (layer "B.Fab")
        (effects (font (size 0.25 0.25) (thickness 0.04)) (justify mirror))
    )
    (fp_text user "Author: Antmicro" (at -0.95 -4.169 270) (layer "B.Fab") hide
        (effects (font (size 0.7 0.7) (thickness 0.15)) (justify left bottom mirror))
    )
    (fp_text user "License: Apache-2.0" (at -0.95 -5.169 270) (layer "B.Fab") hide
        (effects (font (size 0.7 0.7) (thickness 0.15)) (justify left bottom mirror))
    )
    (fp_rect (start -0.925 0.47) (end 0.925 -0.47)
      (stroke (width 0.05) (type default)) (fill none) (layer "B.CrtYd"))
    (fp_rect (start -0.5 0.25) (end 0.5 -0.25)
      (stroke (width 0.15) (type solid)) (fill none) (layer "B.Fab"))
    (pad "1" smd roundrect (at -0.48 0 90) (size 0.59 0.64) (layers "B.Cu" "B.Paste" "B.Mask") (roundrect_rratio 0.25)
      (net 2 "VCC3V3") (pintype "passive"))
    (pad "2" smd roundrect (at 0.48 0 90) (size 0.59 0.64) (layers "B.Cu" "B.Paste" "B.Mask") (roundrect_rratio 0.25)
      (net 145 "QSPIA2_CS_N") (pintype "passive"))
  )
	(footprint "antmicro-footprints:R_0402_1005Metric" (layer "B.Cu")
    (at 80.975 147.8 90)
    (descr "Resistor SMD 0402")
    (tags "resistor SMD 0402")
    (property "Author" "Antmicro")
    (property "License" "Apache-2.0")
    (property "MPN" "CR0402-FX-1001GLF")
    (property "Manufacturer" "Bourns")
    (property "Public" "False")
    (property "Sheetfile" "rot.kicad_sch")
    (property "Sheetname" "RoT")
    (property "Tolerance" "1%")
    (property "Val" "1k")
    (property "ki_description" "SMD Chip Resistor, 1 kohm, ± 1%, 63 mW, 0402 [1005 Metric], Thick Film, General Purpose")
    (property "ki_keywords" "0402, SMT, RESISTOR, PASSIVE")
    (attr smd)
    (fp_text reference "R25" (at -2.75 1.225 270) (layer "B.SilkS")
        (effects (font (size 0.7 0.7) (thickness 0.127)) (justify mirror))
    )
    (fp_text value "R_1k_0402" (at 0 -1.17 270) (layer "B.Fab")
        (effects (font (size 1 1) (thickness 0.15)) (justify mirror))
    )
    (fp_text user "${REFERENCE}" (at 0 0 270) (layer "B.Fab")
        (effects (font (size 0.25 0.25) (thickness 0.04)) (justify mirror))
    )
    (fp_text user "Author: Antmicro" (at -0.95 -4.169 270) (layer "B.Fab") hide
        (effects (font (size 0.7 0.7) (thickness 0.15)) (justify left bottom mirror))
    )
    (fp_text user "License: Apache-2.0" (at -0.95 -5.169 270) (layer "B.Fab") hide
        (effects (font (size 0.7 0.7) (thickness 0.15)) (justify left bottom mirror))
    )
    (fp_rect (start -0.925 0.47) (end 0.925 -0.47)
      (stroke (width 0.05) (type default)) (fill none) (layer "B.CrtYd"))
    (fp_rect (start -0.5 0.25) (end 0.5 -0.25)
      (stroke (width 0.15) (type solid)) (fill none) (layer "B.Fab"))
    (pad "1" smd roundrect (at -0.48 0 90) (size 0.59 0.64) (layers "B.Cu" "B.Paste" "B.Mask") (roundrect_rratio 0.25)
      (net 2 "VCC3V3") (pintype "passive"))
    (pad "2" smd roundrect (at 0.48 0 90) (size 0.59 0.64) (layers "B.Cu" "B.Paste" "B.Mask") (roundrect_rratio 0.25)
      (net 124 "QSPIB_CLK") (pintype "passive"))
  )
	(footprint "antmicro-footprints:R_0402_1005Metric" (layer "B.Cu")
    (at 69.725 138.85 90)
    (descr "Resistor SMD 0402")
    (tags "resistor SMD 0402")
    (property "Author" "Antmicro")
    (property "License" "Apache-2.0")
    (property "MPN" "CR0402-FX-1001GLF")
    (property "Manufacturer" "Bourns")
    (property "Public" "False")
    (property "Sheetfile" "rot.kicad_sch")
    (property "Sheetname" "RoT")
    (property "Tolerance" "1%")
    (property "Val" "1k")
    (property "ki_description" "SMD Chip Resistor, 1 kohm, ± 1%, 63 mW, 0402 [1005 Metric], Thick Film, General Purpose")
    (property "ki_keywords" "0402, SMT, RESISTOR, PASSIVE")
    (attr smd)
    (fp_text reference "R27" (at -2.95 0.243332 90) (layer "B.SilkS")
        (effects (font (size 0.7 0.7) (thickness 0.127)) (justify mirror))
    )
    (fp_text value "R_1k_0402" (at 0 -1.17 90) (layer "B.Fab")
        (effects (font (size 1 1) (thickness 0.15)) (justify mirror))
    )
    (fp_text user "License: Apache-2.0" (at -0.95 -5.169 270) (layer "B.Fab") hide
        (effects (font (size 0.7 0.7) (thickness 0.15)) (justify left bottom mirror))
    )
    (fp_text user "Author: Antmicro" (at -0.95 -4.169 270) (layer "B.Fab") hide
        (effects (font (size 0.7 0.7) (thickness 0.15)) (justify left bottom mirror))
    )
    (fp_text user "${REFERENCE}" (at 0 0 90) (layer "B.Fab")
        (effects (font (size 0.25 0.25) (thickness 0.04)) (justify mirror))
    )
    (fp_rect (start -0.925 0.47) (end 0.925 -0.47)
      (stroke (width 0.05) (type default)) (fill none) (layer "B.CrtYd"))
    (fp_rect (start -0.5 0.25) (end 0.5 -0.25)
      (stroke (width 0.15) (type solid)) (fill none) (layer "B.Fab"))
    (pad "1" smd roundrect (at -0.48 0 90) (size 0.59 0.64) (layers "B.Cu" "B.Paste" "B.Mask") (roundrect_rratio 0.25)
      (net 2 "VCC3V3") (pintype "passive"))
    (pad "2" smd roundrect (at 0.48 0 90) (size 0.59 0.64) (layers "B.Cu" "B.Paste" "B.Mask") (roundrect_rratio 0.25)
      (net 135 "QSPIA_CLK") (pintype "passive"))
  )
)
